# T6G (Grand Teton) — schematic netlist excerpt (pin names and nets, part order shuffled) for the footprints in the layout excerpt that follows; sources: Cadence DE-HDL packaged netlist, KiCad conversion of 04192023_DAF0TMB3IC0_F0TG_MB_C_brd_V02_OCP.brd

C1041  Q_CAP  22UF 4V 20% X6S  pkg C0402  page 312 : A = P0V9_CPU0_RT3_2A ; B = GND
R528  Q_RES  1K 1% CHIP  pkg 0402LF  page 54 : A = PVDD18_S5_P1 ; B = JTAG_CPU1_DBREQ_N

(kicad_pcb
	(version 20260206)
	(generator "pcbnew")
	(generator_version "10.0")
	(general
		(thickness 1.6)
		(legacy_teardrops no)
	)
	(paper "A4")
	(title_block
		(title "04192023_DAF0TMB3IC0_F0TG_MB_C_brd_V02_OCP.brd")
		(comment 1 "Grand Teton / footprints 7998-7999 of 8354")
	)
	(layers
		(0 "F.Cu" signal "TOP")
		(4 "In1.Cu" signal "GND")
		(6 "In2.Cu" signal "IN1")
		(8 "In3.Cu" signal "GND1")
		(10 "In4.Cu" signal "IN2")
		(12 "In5.Cu" signal "GND2")
		(14 "In6.Cu" signal "IN3")
		(16 "In7.Cu" signal "GND3")
		(18 "In8.Cu" signal "VCC")
		(20 "In9.Cu" signal "VCC1")
		(22 "In10.Cu" signal "GND4")
		(24 "In11.Cu" signal "IN4")
		(26 "In12.Cu" signal "GND5")
		(28 "In13.Cu" signal "IN5")
		(30 "In14.Cu" signal "GND6")
		(32 "In15.Cu" signal "IN6")
		(34 "In16.Cu" signal "GND7")
		(2 "B.Cu" signal "BOTTOM")
		(9 "F.Adhes" user "F.Adhesive")
		(11 "B.Adhes" user "B.Adhesive")
		(13 "F.Paste" user "Package Geometry/Pastemask Top")
		(15 "B.Paste" user "Package Geometry/Pastemask Bottom")
		(5 "F.SilkS" user "Ref Des/Silkscreen Top")
		(7 "B.SilkS" user "Ref Des/Silkscreen Bottom")
		(1 "F.Mask" user "Board Geometry/Soldermask Top")
		(3 "B.Mask" user "Board Geometry/Soldermask Bottom")
		(17 "Dwgs.User" user "User.Drawings")
		(19 "Cmts.User" user "User.Comments")
		(21 "Eco1.User" user "User.Eco1")
		(23 "Eco2.User" user "User.Eco2")
		(25 "Edge.Cuts" user "Board Geometry/Outline")
		(27 "Margin" user)
		(31 "F.CrtYd" user "Package Geometry/Place Bound Top")
		(29 "B.CrtYd" user "Package Geometry/Place Bound Bottom")
		(35 "F.Fab" user "Ref Des/Assembly Top")
		(33 "B.Fab" user "Ref Des/Assembly Bottom")
	)
	(footprint ""
		(layer "B.Cu")
		(at 375.29135 -398.942052 90)
		(property "Reference" "C1041"
			(at 0 0 90)
			(layer "B.SilkS")
			(hide yes)
			(effects
				(font
					(size 1.27 1.27)
				)
				(justify mirror)
			)
		)
		(property "Value" ""
			(at 0 0 90)
			(layer "B.Fab")
			(effects
				(font
					(size 1.27 1.27)
				)
				(justify mirror)
			)
		)
		(duplicate_pad_numbers_are_jumpers no)
		(fp_line
			(start 0.7874 -0.4064)
			(end -0.7874 -0.4064)
			(stroke
				(width 0.1524)
				(type default)
			)
			(layer "B.SilkS")
		)
		(fp_line
			(start -0.7874 -0.4064)
			(end -0.7874 0.4064)
			(stroke
				(width 0.1524)
				(type default)
			)
			(layer "B.SilkS")
		)
		(fp_line
			(start 0.7874 0.4064)
			(end 0.7874 -0.4064)
			(stroke
				(width 0.1524)
				(type default)
			)
			(layer "B.SilkS")
		)
		(fp_line
			(start -0.7874 0.4064)
			(end 0.7874 0.4064)
			(stroke
				(width 0.1524)
				(type default)
			)
			(layer "B.SilkS")
		)
		(fp_line
			(start 0.67945 -0.305054)
			(end 0.12065 -0.305054)
			(stroke
				(width 0.1)
				(type default)
			)
			(layer "B.Fab")
		)
		(fp_line
			(start 0.12065 -0.305054)
			(end 0.12065 -0.2794)
			(stroke
				(width 0.1)
				(type default)
			)
			(layer "B.Fab")
		)
		(fp_line
			(start -0.12065 -0.3048)
			(end -0.67945 -0.3048)
			(stroke
				(width 0.1)
				(type default)
			)
			(layer "B.Fab")
		)
		(fp_line
			(start -0.67945 -0.3048)
			(end -0.67945 0.3048)
			(stroke
				(width 0.1)
				(type default)
			)
			(layer "B.Fab")
		)
		(fp_line
			(start 0.12065 -0.2794)
			(end -0.12065 -0.2794)
			(stroke
				(width 0.1)
				(type default)
			)
			(layer "B.Fab")
		)
		(fp_line
			(start -0.12065 -0.2794)
			(end -0.12065 -0.3048)
			(stroke
				(width 0.1)
				(type default)
			)
			(layer "B.Fab")
		)
		(fp_line
			(start 0.12065 0.2794)
			(end 0.12065 0.3048)
			(stroke
				(width 0.1)
				(type default)
			)
			(layer "B.Fab")
		)
		(fp_line
			(start -0.120396 0.2794)
			(end 0.12065 0.2794)
			(stroke
				(width 0.1)
				(type default)
			)
			(layer "B.Fab")
		)
		(fp_line
			(start 0.67945 0.3048)
			(end 0.67945 -0.305054)
			(stroke
				(width 0.1)
				(type default)
			)
			(layer "B.Fab")
		)
		(fp_line
			(start 0.12065 0.3048)
			(end 0.67945 0.3048)
			(stroke
				(width 0.1)
				(type default)
			)
			(layer "B.Fab")
		)
		(fp_line
			(start -0.120396 0.3048)
			(end -0.120396 0.2794)
			(stroke
				(width 0.1)
				(type default)
			)
			(layer "B.Fab")
		)
		(fp_line
			(start -0.67945 0.3048)
			(end -0.120396 0.3048)
			(stroke
				(width 0.1)
				(type default)
			)
			(layer "B.Fab")
		)
		(pad "1" smd circle
			(at 0.40005 0 270)
			(size 0 0)
			(layers "B.Cu" "B.Mask" "B.Paste")
			(net "P0V9_CPU0_RT3_2A")
		)
		(pad "2" smd circle
			(at -0.40005 0 270)
			(size 0 0)
			(layers "B.Cu" "B.Mask" "B.Paste")
			(net "GND")
		)
	)
	(footprint ""
		(layer "B.Cu")
		(at 149.243034 -203.704952 90)
		(property "Reference" "R528"
			(at 0 0 90)
			(layer "B.SilkS")
			(hide yes)
			(effects
				(font
					(size 1.27 1.27)
				)
				(justify mirror)
			)
		)
		(property "Value" ""
			(at 0 0 90)
			(layer "B.Fab")
			(effects
				(font
					(size 1.27 1.27)
				)
				(justify mirror)
			)
		)
		(duplicate_pad_numbers_are_jumpers no)
		(fp_line
			(start 0.7874 -0.4064)
			(end -0.7874 -0.4064)
			(stroke
				(width 0.1524)
				(type default)
			)
			(layer "B.SilkS")
		)
		(fp_line
			(start -0.7874 -0.4064)
			(end -0.7874 0.4064)
			(stroke
				(width 0.1524)
				(type default)
			)
			(layer "B.SilkS")
		)
		(fp_line
			(start 0.7874 0.4064)
			(end 0.7874 -0.4064)
			(stroke
				(width 0.1524)
				(type default)
			)
			(layer "B.SilkS")
		)
		(fp_line
			(start -0.7874 0.4064)
			(end 0.7874 0.4064)
			(stroke
				(width 0.1524)
				(type default)
			)
			(layer "B.SilkS")
		)
		(fp_line
			(start 0.67945 -0.305054)
			(end 0.12065 -0.305054)
			(stroke
				(width 0.1)
				(type default)
			)
			(layer "B.Fab")
		)
		(fp_line
			(start 0.12065 -0.305054)
			(end 0.12065 -0.2794)
			(stroke
				(width 0.1)
				(type default)
			)
			(layer "B.Fab")
		)
		(fp_line
			(start -0.12065 -0.3048)
			(end -0.67945 -0.3048)
			(stroke
				(width 0.1)
				(type default)
			)
			(layer "B.Fab")
		)
		(fp_line
			(start -0.67945 -0.3048)
			(end -0.67945 0.3048)
			(stroke
				(width 0.1)
				(type default)
			)
			(layer "B.Fab")
		)
		(fp_line
			(start 0.12065 -0.2794)
			(end -0.12065 -0.2794)
			(stroke
				(width 0.1)
				(type default)
			)
			(layer "B.Fab")
		)
		(fp_line
			(start -0.12065 -0.2794)
			(end -0.12065 -0.3048)
			(stroke
				(width 0.1)
				(type default)
			)
			(layer "B.Fab")
		)
		(fp_line
			(start 0.12065 0.2794)
			(end 0.12065 0.3048)
			(stroke
				(width 0.1)
				(type default)
			)
			(layer "B.Fab")
		)
		(fp_line
			(start -0.120396 0.2794)
			(end 0.12065 0.2794)
			(stroke
				(width 0.1)
				(type default)
			)
			(layer "B.Fab")
		)
		(fp_line
			(start 0.67945 0.3048)
			(end 0.67945 -0.305054)
			(stroke
				(width 0.1)
				(type default)
			)
			(layer "B.Fab")
		)
		(fp_line
			(start 0.12065 0.3048)
			(end 0.67945 0.3048)
			(stroke
				(width 0.1)
				(type default)
			)
			(layer "B.Fab")
		)
		(fp_line
			(start -0.120396 0.3048)
			(end -0.120396 0.2794)
			(stroke
				(width 0.1)
				(type default)
			)
			(layer "B.Fab")
		)
		(fp_line
			(start -0.67945 0.3048)
			(end -0.120396 0.3048)
			(stroke
				(width 0.1)
				(type default)
			)
			(layer "B.Fab")
		)
		(pad "1" smd circle
			(at 0.40005 0 270)
			(size 0 0)
			(layers "B.Cu" "B.Mask" "B.Paste")
			(net "PVDD18_S5_P1")
		)
		(pad "2" smd circle
			(at -0.40005 0 270)
			(size 0 0)
			(layers "B.Cu" "B.Mask" "B.Paste")
			(net "JTAG_CPU1_DBREQ_N")
		)
	)
)
